(kicad_pcb
	(version 20260206)
	(generator "pcbnew")
	(generator_version "10.0")
	(general
		(thickness 1.6)
		(legacy_teardrops no)
	)
	(paper "A4")
	(title_block
		(title "peb — Lightning_PEB_BRD.brd")
		(comment 1 "Lightning (Wiwynn / Facebook NVMe JBOF) / footprints 254-260 of 2563")
	)
	(layers
		(0 "F.Cu" signal "TOP")
		(4 "In1.Cu" signal "L2GND")
		(6 "In2.Cu" signal "L3")
		(8 "In3.Cu" signal "L4VCC")
		(10 "In4.Cu" signal "L5VCC")
		(12 "In5.Cu" signal "L6")
		(14 "In6.Cu" signal "L7GND")
		(2 "B.Cu" signal "BOTTOM")
		(9 "F.Adhes" user "F.Adhesive")
		(11 "B.Adhes" user "B.Adhesive")
		(13 "F.Paste" user "Package Geometry/Pastemask Top")
		(15 "B.Paste" user "Package Geometry/Pastemask Bottom")
		(5 "F.SilkS" user "Ref Des/Silkscreen Top")
		(7 "B.SilkS" user "Ref Des/Silkscreen Bottom")
		(1 "F.Mask" user "Board Geometry/Soldermask Top")
		(3 "B.Mask" user "Board Geometry/Soldermask Bottom")
		(17 "Dwgs.User" user "User.Drawings")
		(19 "Cmts.User" user "User.Comments")
		(21 "Eco1.User" user "User.Eco1")
		(23 "Eco2.User" user "User.Eco2")
		(25 "Edge.Cuts" user "Board Geometry/Outline")
		(27 "Margin" user)
		(31 "F.CrtYd" user "Package Geometry/Place Bound Top")
		(29 "B.CrtYd" user "Package Geometry/Place Bound Bottom")
		(35 "F.Fab" user "Ref Des/Assembly Top")
		(33 "B.Fab" user "Ref Des/Assembly Bottom")
	)
	(footprint ""
		(layer "F.Cu")
		(at 166.116 -93.2434 90)
		(property "Reference" "R3107"
			(at 0 0 90)
			(layer "F.SilkS")
			(hide yes)
			(effects
				(font
					(size 1.27 1.27)
				)
			)
		)
		(property "Value" "27R2F-GP"
			(at 0.064008 -3.993896 90)
			(unlocked yes)
			(layer "F.Fab")
			(hide yes)
			(effects
				(font
					(size 1.016 1.016)
					(thickness 0.1524)
				)
			)
		)
		(property "Device Type" "R402H16"
			(at 0.064008 -5.517896 90)
			(unlocked yes)
			(layer "F.Fab")
			(hide yes)
			(effects
				(font
					(size 1.016 1.016)
					(thickness 0.1524)
				)
			)
		)
		(duplicate_pad_numbers_are_jumpers no)
		(fp_line
			(start 0.508 -0.9398)
			(end -0.508 -0.9398)
			(stroke
				(width 0.1524)
				(type default)
			)
			(layer "F.SilkS")
		)
		(fp_line
			(start -0.508 -0.9398)
			(end -0.508 0.9398)
			(stroke
				(width 0.1524)
				(type default)
			)
			(layer "F.SilkS")
		)
		(fp_rect
			(start -0.508 0.9398)
			(end 0.508 -0.9398)
			(stroke
				(width 0)
				(type default)
			)
			(fill no)
			(layer "F.CrtYd")
		)
		(fp_rect
			(start -0.508 0.9398)
			(end 0.508 -0.9398)
			(stroke
				(width 0)
				(type default)
			)
			(fill no)
			(layer "F.Fab")
		)
		(pad "1" smd custom
			(at 0 -0.4445 90)
			(size 0.1397 0.1397)
			(layers "F.Cu" "F.Mask" "F.Paste")
			(net "CLKGEN_N2_R")
			(options
				(clearance outline)
				(anchor circle)
			)
			(primitives
				(gr_poly
					(pts
						(arc
							(start -0.1778 -0.2794)
							(mid -0.249642 -0.249642)
							(end -0.2794 -0.1778)
						)
						(arc
							(start -0.2794 0.1778)
							(mid -0.249642 0.249642)
							(end -0.1778 0.2794)
						)
						(arc
							(start 0.1778 0.2794)
							(mid 0.249642 0.249642)
							(end 0.2794 0.1778)
						)
						(arc
							(start 0.2794 -0.1778)
							(mid 0.249642 -0.249642)
							(end 0.1778 -0.2794)
						)
					)
					(width 0)
					(fill yes)
				)
			)
		)
		(pad "2" smd custom
			(at 0 0.4445 90)
			(size 0.1397 0.1397)
			(layers "F.Cu" "F.Mask" "F.Paste")
			(net "CLKGEN_N2")
			(options
				(clearance outline)
				(anchor circle)
			)
			(primitives
				(gr_poly
					(pts
						(arc
							(start -0.1778 -0.2794)
							(mid -0.249642 -0.249642)
							(end -0.2794 -0.1778)
						)
						(arc
							(start -0.2794 0.1778)
							(mid -0.249642 0.249642)
							(end -0.1778 0.2794)
						)
						(arc
							(start 0.1778 0.2794)
							(mid 0.249642 0.249642)
							(end 0.2794 0.1778)
						)
						(arc
							(start 0.2794 -0.1778)
							(mid 0.249642 -0.249642)
							(end 0.1778 -0.2794)
						)
					)
					(width 0)
					(fill yes)
				)
			)
		)
	)
	(footprint ""
		(layer "F.Cu")
		(at 26.035 -74.9046 90)
		(property "Reference" "R376"
			(at 0 0 90)
			(layer "F.SilkS")
			(hide yes)
			(effects
				(font
					(size 1.27 1.27)
				)
			)
		)
		(property "Value" "0R2J-2-GP"
			(at 0.064008 -3.993896 90)
			(unlocked yes)
			(layer "F.Fab")
			(hide yes)
			(effects
				(font
					(size 1.016 1.016)
					(thickness 0.1524)
				)
			)
		)
		(property "Device Type" "R402H16"
			(at 0.064008 -5.517896 90)
			(unlocked yes)
			(layer "F.Fab")
			(hide yes)
			(effects
				(font
					(size 1.016 1.016)
					(thickness 0.1524)
				)
			)
		)
		(duplicate_pad_numbers_are_jumpers no)
		(fp_line
			(start 0.508 -0.9398)
			(end -0.508 -0.9398)
			(stroke
				(width 0.1524)
				(type default)
			)
			(layer "F.SilkS")
		)
		(fp_line
			(start -0.508 -0.9398)
			(end -0.508 0.9398)
			(stroke
				(width 0.1524)
				(type default)
			)
			(layer "F.SilkS")
		)
		(fp_rect
			(start -0.508 0.9398)
			(end 0.508 -0.9398)
			(stroke
				(width 0)
				(type default)
			)
			(fill no)
			(layer "F.CrtYd")
		)
		(fp_rect
			(start -0.508 0.9398)
			(end 0.508 -0.9398)
			(stroke
				(width 0)
				(type default)
			)
			(fill no)
			(layer "F.Fab")
		)
		(pad "1" smd custom
			(at 0 -0.4445 90)
			(size 0.1397 0.1397)
			(layers "F.Cu" "F.Mask" "F.Paste")
			(net "RMII_PHY_BMC_RXD0_R")
			(options
				(clearance outline)
				(anchor circle)
			)
			(primitives
				(gr_poly
					(pts
						(arc
							(start -0.1778 -0.2794)
							(mid -0.249642 -0.249642)
							(end -0.2794 -0.1778)
						)
						(arc
							(start -0.2794 0.1778)
							(mid -0.249642 0.249642)
							(end -0.1778 0.2794)
						)
						(arc
							(start 0.1778 0.2794)
							(mid 0.249642 0.249642)
							(end 0.2794 0.1778)
						)
						(arc
							(start 0.2794 -0.1778)
							(mid 0.249642 -0.249642)
							(end 0.1778 -0.2794)
						)
					)
					(width 0)
					(fill yes)
				)
			)
		)
		(pad "2" smd custom
			(at 0 0.4445 90)
			(size 0.1397 0.1397)
			(layers "F.Cu" "F.Mask" "F.Paste")
			(net "RMII_PHY_BMC_RXD0")
			(options
				(clearance outline)
				(anchor circle)
			)
			(primitives
				(gr_poly
					(pts
						(arc
							(start -0.1778 -0.2794)
							(mid -0.249642 -0.249642)
							(end -0.2794 -0.1778)
						)
						(arc
							(start -0.2794 0.1778)
							(mid -0.249642 0.249642)
							(end -0.1778 0.2794)
						)
						(arc
							(start 0.1778 0.2794)
							(mid 0.249642 0.249642)
							(end 0.2794 0.1778)
						)
						(arc
							(start 0.2794 -0.1778)
							(mid 0.249642 -0.249642)
							(end 0.1778 -0.2794)
						)
					)
					(width 0)
					(fill yes)
				)
			)
		)
	)
	(footprint ""
		(layer "F.Cu")
		(at 57.318148 -125.8062 90)
		(property "Reference" "R707"
			(at 0 0 90)
			(layer "F.SilkS")
			(hide yes)
			(effects
				(font
					(size 1.27 1.27)
				)
			)
		)
		(property "Value" "0R2J-2-GP"
			(at 0.064008 -3.993896 90)
			(unlocked yes)
			(layer "F.Fab")
			(hide yes)
			(effects
				(font
					(size 1.016 1.016)
					(thickness 0.1524)
				)
			)
		)
		(property "Device Type" "R402H16"
			(at 0.064008 -5.517896 90)
			(unlocked yes)
			(layer "F.Fab")
			(hide yes)
			(effects
				(font
					(size 1.016 1.016)
					(thickness 0.1524)
				)
			)
		)
		(duplicate_pad_numbers_are_jumpers no)
		(fp_line
			(start 0.508 -0.9398)
			(end -0.508 -0.9398)
			(stroke
				(width 0.1524)
				(type default)
			)
			(layer "F.SilkS")
		)
		(fp_line
			(start -0.508 -0.9398)
			(end -0.508 0.9398)
			(stroke
				(width 0.1524)
				(type default)
			)
			(layer "F.SilkS")
		)
		(fp_rect
			(start -0.508 0.9398)
			(end 0.508 -0.9398)
			(stroke
				(width 0)
				(type default)
			)
			(fill no)
			(layer "F.CrtYd")
		)
		(fp_rect
			(start -0.508 0.9398)
			(end 0.508 -0.9398)
			(stroke
				(width 0)
				(type default)
			)
			(fill no)
			(layer "F.Fab")
		)
		(pad "1" smd custom
			(at 0 -0.4445 90)
			(size 0.1397 0.1397)
			(layers "F.Cu" "F.Mask" "F.Paste")
			(net "I2C_MUX_RESET_PEB_R")
			(options
				(clearance outline)
				(anchor circle)
			)
			(primitives
				(gr_poly
					(pts
						(arc
							(start -0.1778 -0.2794)
							(mid -0.249642 -0.249642)
							(end -0.2794 -0.1778)
						)
						(arc
							(start -0.2794 0.1778)
							(mid -0.249642 0.249642)
							(end -0.1778 0.2794)
						)
						(arc
							(start 0.1778 0.2794)
							(mid 0.249642 0.249642)
							(end 0.2794 0.1778)
						)
						(arc
							(start 0.2794 -0.1778)
							(mid 0.249642 -0.249642)
							(end 0.1778 -0.2794)
						)
					)
					(width 0)
					(fill yes)
				)
			)
		)
		(pad "2" smd custom
			(at 0 0.4445 90)
			(size 0.1397 0.1397)
			(layers "F.Cu" "F.Mask" "F.Paste")
			(net "I2C_MUX_RESET_PEB")
			(options
				(clearance outline)
				(anchor circle)
			)
			(primitives
				(gr_poly
					(pts
						(arc
							(start -0.1778 -0.2794)
							(mid -0.249642 -0.249642)
							(end -0.2794 -0.1778)
						)
						(arc
							(start -0.2794 0.1778)
							(mid -0.249642 0.249642)
							(end -0.1778 0.2794)
						)
						(arc
							(start 0.1778 0.2794)
							(mid 0.249642 0.249642)
							(end 0.2794 0.1778)
						)
						(arc
							(start 0.2794 -0.1778)
							(mid 0.249642 -0.249642)
							(end 0.1778 -0.2794)
						)
					)
					(width 0)
					(fill yes)
				)
			)
		)
	)
	(footprint ""
		(layer "F.Cu")
		(at 192.5574 -6.6548 90)
		(property "Reference" "R305"
			(at 0 0 90)
			(layer "F.SilkS")
			(hide yes)
			(effects
				(font
					(size 1.27 1.27)
				)
			)
		)
		(property "Value" "0R2J-2-GP"
			(at 0.064008 -3.993896 90)
			(unlocked yes)
			(layer "F.Fab")
			(hide yes)
			(effects
				(font
					(size 1.016 1.016)
					(thickness 0.1524)
				)
			)
		)
		(property "Device Type" "R402H16"
			(at 0.064008 -5.517896 90)
			(unlocked yes)
			(layer "F.Fab")
			(hide yes)
			(effects
				(font
					(size 1.016 1.016)
					(thickness 0.1524)
				)
			)
		)
		(duplicate_pad_numbers_are_jumpers no)
		(fp_line
			(start 0.508 -0.9398)
			(end -0.508 -0.9398)
			(stroke
				(width 0.1524)
				(type default)
			)
			(layer "F.SilkS")
		)
		(fp_line
			(start -0.508 -0.9398)
			(end -0.508 0.9398)
			(stroke
				(width 0.1524)
				(type default)
			)
			(layer "F.SilkS")
		)
		(fp_rect
			(start -0.508 0.9398)
			(end 0.508 -0.9398)
			(stroke
				(width 0)
				(type default)
			)
			(fill no)
			(layer "F.CrtYd")
		)
		(fp_rect
			(start -0.508 0.9398)
			(end 0.508 -0.9398)
			(stroke
				(width 0)
				(type default)
			)
			(fill no)
			(layer "F.Fab")
		)
		(pad "1" smd custom
			(at 0 -0.4445 90)
			(size 0.1397 0.1397)
			(layers "F.Cu" "F.Mask" "F.Paste")
			(net "HB_OUT_R")
			(options
				(clearance outline)
				(anchor circle)
			)
			(primitives
				(gr_poly
					(pts
						(arc
							(start -0.1778 -0.2794)
							(mid -0.249642 -0.249642)
							(end -0.2794 -0.1778)
						)
						(arc
							(start -0.2794 0.1778)
							(mid -0.249642 0.249642)
							(end -0.1778 0.2794)
						)
						(arc
							(start 0.1778 0.2794)
							(mid 0.249642 0.249642)
							(end 0.2794 0.1778)
						)
						(arc
							(start 0.2794 -0.1778)
							(mid 0.249642 -0.249642)
							(end 0.1778 -0.2794)
						)
					)
					(width 0)
					(fill yes)
				)
			)
		)
		(pad "2" smd custom
			(at 0 0.4445 90)
			(size 0.1397 0.1397)
			(layers "F.Cu" "F.Mask" "F.Paste")
			(net "HB_OUT")
			(options
				(clearance outline)
				(anchor circle)
			)
			(primitives
				(gr_poly
					(pts
						(arc
							(start -0.1778 -0.2794)
							(mid -0.249642 -0.249642)
							(end -0.2794 -0.1778)
						)
						(arc
							(start -0.2794 0.1778)
							(mid -0.249642 0.249642)
							(end -0.1778 0.2794)
						)
						(arc
							(start 0.1778 0.2794)
							(mid 0.249642 0.249642)
							(end 0.2794 0.1778)
						)
						(arc
							(start 0.2794 -0.1778)
							(mid 0.249642 -0.249642)
							(end 0.1778 -0.2794)
						)
					)
					(width 0)
					(fill yes)
				)
			)
		)
	)
	(footprint ""
		(layer "F.Cu")
		(at 48.954182 -116.797328)
		(property "Reference" "R806"
			(at 0 0 0)
			(layer "F.SilkS")
			(hide yes)
			(effects
				(font
					(size 1.27 1.27)
				)
			)
		)
		(property "Value" "0R2J-2-GP"
			(at 0.064008 -3.993896 0)
			(unlocked yes)
			(layer "F.Fab")
			(hide yes)
			(effects
				(font
					(size 1.016 1.016)
					(thickness 0.1524)
				)
			)
		)
		(property "Device Type" "R402H16"
			(at 0.064008 -5.517896 0)
			(unlocked yes)
			(layer "F.Fab")
			(hide yes)
			(effects
				(font
					(size 1.016 1.016)
					(thickness 0.1524)
				)
			)
		)
		(duplicate_pad_numbers_are_jumpers no)
		(fp_line
			(start -0.508 -0.9398)
			(end -0.508 0.9398)
			(stroke
				(width 0.1524)
				(type default)
			)
			(layer "F.SilkS")
		)
		(fp_line
			(start 0.508 -0.9398)
			(end -0.508 -0.9398)
			(stroke
				(width 0.1524)
				(type default)
			)
			(layer "F.SilkS")
		)
		(fp_rect
			(start -0.508 0.9398)
			(end 0.508 -0.9398)
			(stroke
				(width 0)
				(type default)
			)
			(fill no)
			(layer "F.CrtYd")
		)
		(fp_rect
			(start -0.508 0.9398)
			(end 0.508 -0.9398)
			(stroke
				(width 0)
				(type default)
			)
			(fill no)
			(layer "F.Fab")
		)
		(pad "1" smd custom
			(at 0 -0.4445)
			(size 0.1397 0.1397)
			(layers "F.Cu" "F.Mask" "F.Paste")
			(net "DP_BMC_CPU_RST_N_R")
			(options
				(clearance outline)
				(anchor circle)
			)
			(primitives
				(gr_poly
					(pts
						(arc
							(start -0.1778 -0.2794)
							(mid -0.249642 -0.249642)
							(end -0.2794 -0.1778)
						)
						(arc
							(start -0.2794 0.1778)
							(mid -0.249642 0.249642)
							(end -0.1778 0.2794)
						)
						(arc
							(start 0.1778 0.2794)
							(mid 0.249642 0.249642)
							(end 0.2794 0.1778)
						)
						(arc
							(start 0.2794 -0.1778)
							(mid 0.249642 -0.249642)
							(end 0.1778 -0.2794)
						)
					)
					(width 0)
					(fill yes)
				)
			)
		)
		(pad "2" smd custom
			(at 0 0.4445)
			(size 0.1397 0.1397)
			(layers "F.Cu" "F.Mask" "F.Paste")
			(net "BMC_USB_EN_1")
			(options
				(clearance outline)
				(anchor circle)
			)
			(primitives
				(gr_poly
					(pts
						(arc
							(start -0.1778 -0.2794)
							(mid -0.249642 -0.249642)
							(end -0.2794 -0.1778)
						)
						(arc
							(start -0.2794 0.1778)
							(mid -0.249642 0.249642)
							(end -0.1778 0.2794)
						)
						(arc
							(start 0.1778 0.2794)
							(mid 0.249642 0.249642)
							(end 0.2794 0.1778)
						)
						(arc
							(start 0.2794 -0.1778)
							(mid 0.249642 -0.249642)
							(end 0.1778 -0.2794)
						)
					)
					(width 0)
					(fill yes)
				)
			)
		)
	)
	(footprint ""
		(layer "F.Cu")
		(at 42.9768 -187.5536 90)
		(property "Reference" "U29"
			(at 0 0 90)
			(layer "F.SilkS")
			(hide yes)
			(effects
				(font
					(size 1.27 1.27)
				)
			)
		)
		(property "Value" "PCA9511ADP-T-GP"
			(at 0 -13.1572 90)
			(unlocked yes)
			(layer "F.Fab")
			(hide yes)
			(effects
				(font
					(size 1.016 1.016)
					(thickness 0.1524)
				)
			)
		)
		(property "Device Type" "SSOIC8-2H44"
			(at 0 -15.1892 90)
			(unlocked yes)
			(layer "F.Fab")
			(hide yes)
			(effects
				(font
					(size 1.016 1.016)
					(thickness 0.1524)
				)
			)
		)
		(duplicate_pad_numbers_are_jumpers no)
		(fp_line
			(start 1.0922 -1.016)
			(end 1.0922 1.016)
			(stroke
				(width 0.1524)
				(type default)
			)
			(layer "F.SilkS")
		)
		(fp_line
			(start -1.9304 -1.016)
			(end 1.0922 -1.016)
			(stroke
				(width 0.1524)
				(type default)
			)
			(layer "F.SilkS")
		)
		(fp_line
			(start -1.524 0)
			(end -1.9304 -0.4064)
			(stroke
				(width 0.1524)
				(type default)
			)
			(layer "F.SilkS")
		)
		(fp_line
			(start -1.524 0)
			(end -1.9304 0.4064)
			(stroke
				(width 0.1524)
				(type default)
			)
			(layer "F.SilkS")
		)
		(fp_line
			(start 1.0922 1.016)
			(end -1.9304 1.016)
			(stroke
				(width 0.1524)
				(type default)
			)
			(layer "F.SilkS")
		)
		(fp_line
			(start -1.9304 1.016)
			(end -1.9304 -1.016)
			(stroke
				(width 0.1524)
				(type default)
			)
			(layer "F.SilkS")
		)
		(fp_line
			(start -1.7018 1.0414)
			(end -1.7018 2.9718)
			(stroke
				(width 0.635)
				(type default)
			)
			(layer "F.SilkS")
		)
		(fp_poly
			(pts
				(xy -1.1938 -1.016) (xy 1.0922 -1.016) (xy 1.0922 1.016) (xy -1.1938 1.016)
			)
			(stroke
				(width 0)
				(type default)
			)
			(fill yes)
			(layer "F.SilkS")
		)
		(fp_rect
			(start -2.0066 3.3401)
			(end 2.0066 -3.3401)
			(stroke
				(width 0)
				(type default)
			)
			(fill no)
			(layer "F.CrtYd")
		)
		(fp_poly
			(pts
				(xy -2.0066 -3.3401) (xy 2.0066 -3.3401) (xy 2.0066 3.3401) (xy -2.0066 3.3401)
			)
			(stroke
				(width 0)
				(type default)
			)
			(fill no)
			(layer "F.Fab")
		)
		(pad "1" smd rect
			(at -0.97536 2.0701 90)
			(size 0.4064 1.524)
			(layers "F.Cu" "F.Mask" "F.Paste")
			(net "I2C9_BUFF_EN")
		)
		(pad "2" smd rect
			(at -0.32512 2.0701 90)
			(size 0.4064 1.524)
			(layers "F.Cu" "F.Mask" "F.Paste")
			(net "BMC_I2C9_CLKBUF2_SCL_R")
		)
		(pad "3" smd rect
			(at 0.32512 2.0701 90)
			(size 0.4064 1.524)
			(layers "F.Cu" "F.Mask" "F.Paste")
			(net "BUF_I2C9_CLKBUF2_SCL_R")
		)
		(pad "4" smd rect
			(at 0.97536 2.0701 90)
			(size 0.4064 1.524)
			(layers "F.Cu" "F.Mask" "F.Paste")
			(net "GND")
		)
		(pad "5" smd rect
			(at 0.97536 -2.0701 90)
			(size 0.4064 1.524)
			(layers "F.Cu" "F.Mask" "F.Paste")
			(net "I2C9_BUF_READY")
		)
		(pad "6" smd rect
			(at 0.32512 -2.0701 90)
			(size 0.4064 1.524)
			(layers "F.Cu" "F.Mask" "F.Paste")
			(net "BUF_I2C9_CLKBUF2_SDA_R")
		)
		(pad "7" smd rect
			(at -0.32512 -2.0701 90)
			(size 0.4064 1.524)
			(layers "F.Cu" "F.Mask" "F.Paste")
			(net "BMC_I2C9_CLKBUF2_SDA_R")
		)
		(pad "8" smd rect
			(at -0.97536 -2.0701 90)
			(size 0.4064 1.524)
			(layers "F.Cu" "F.Mask" "F.Paste")
			(net "P3V3_STBY")
		)
	)
	(footprint ""
		(layer "F.Cu")
		(at 74.779124 -183.235092)
		(property "Reference" "R7981"
			(at 0 0 0)
			(layer "F.SilkS")
			(hide yes)
			(effects
				(font
					(size 1.27 1.27)
				)
			)
		)
		(property "Value" "0R2J-2-GP"
			(at 0.064008 -3.993896 0)
			(unlocked yes)
			(layer "F.Fab")
			(hide yes)
			(effects
				(font
					(size 1.016 1.016)
					(thickness 0.1524)
				)
			)
		)
		(property "Device Type" "R402H16"
			(at 0.064008 -5.517896 0)
			(unlocked yes)
			(layer "F.Fab")
			(hide yes)
			(effects
				(font
					(size 1.016 1.016)
					(thickness 0.1524)
				)
			)
		)
		(duplicate_pad_numbers_are_jumpers no)
		(fp_line
			(start -0.508 -0.9398)
			(end -0.508 0.9398)
			(stroke
				(width 0.1524)
				(type default)
			)
			(layer "F.SilkS")
		)
		(fp_line
			(start 0.508 -0.9398)
			(end -0.508 -0.9398)
			(stroke
				(width 0.1524)
				(type default)
			)
			(layer "F.SilkS")
		)
		(fp_rect
			(start -0.508 0.9398)
			(end 0.508 -0.9398)
			(stroke
				(width 0)
				(type default)
			)
			(fill no)
			(layer "F.CrtYd")
		)
		(fp_rect
			(start -0.508 0.9398)
			(end 0.508 -0.9398)
			(stroke
				(width 0)
				(type default)
			)
			(fill no)
			(layer "F.Fab")
		)
		(pad "1" smd custom
			(at 0 -0.4445)
			(size 0.1397 0.1397)
			(layers "F.Cu" "F.Mask" "F.Paste")
			(net "SSD_PERST#0")
			(options
				(clearance outline)
				(anchor circle)
			)
			(primitives
				(gr_poly
					(pts
						(arc
							(start -0.1778 -0.2794)
							(mid -0.249642 -0.249642)
							(end -0.2794 -0.1778)
						)
						(arc
							(start -0.2794 0.1778)
							(mid -0.249642 0.249642)
							(end -0.1778 0.2794)
						)
						(arc
							(start 0.1778 0.2794)
							(mid 0.249642 0.249642)
							(end 0.2794 0.1778)
						)
						(arc
							(start 0.2794 -0.1778)
							(mid 0.249642 -0.249642)
							(end 0.1778 -0.2794)
						)
					)
					(width 0)
					(fill yes)
				)
			)
		)
		(pad "2" smd custom
			(at 0 0.4445)
			(size 0.1397 0.1397)
			(layers "F.Cu" "F.Mask" "F.Paste")
			(net "SSD_PERST#0_R")
			(options
				(clearance outline)
				(anchor circle)
			)
			(primitives
				(gr_poly
					(pts
						(arc
							(start -0.1778 -0.2794)
							(mid -0.249642 -0.249642)
							(end -0.2794 -0.1778)
						)
						(arc
							(start -0.2794 0.1778)
							(mid -0.249642 0.249642)
							(end -0.1778 0.2794)
						)
						(arc
							(start 0.1778 0.2794)
							(mid 0.249642 0.249642)
							(end 0.2794 0.1778)
						)
						(arc
							(start 0.2794 -0.1778)
							(mid 0.249642 -0.249642)
							(end 0.1778 -0.2794)
						)
					)
					(width 0)
					(fill yes)
				)
			)
		)
	)
)
